(kicad_pcb
	(version 20241229)
	(generator "pcbnew")
	(generator_version "9.0")
	(general
		(thickness 1.63)
		(legacy_teardrops no)
	)
	(paper "A4")
	(title_block
		(title "CM4 Baseboard")
		(date "2026-01-05")
		(rev "1.1.1")
		(company "Antmicro Ltd")
		(comment 1 "www.antmicro.com")
		(comment 9 "footprints 413-416 of 506")
	)
	(layers
		(0 "F.Cu" signal)
		(4 "In1.Cu" power)
		(6 "In2.Cu" power)
		(8 "In3.Cu" signal)
		(10 "In4.Cu" signal)
		(2 "B.Cu" signal)
		(9 "F.Adhes" user "F.Adhesive")
		(11 "B.Adhes" user "B.Adhesive")
		(13 "F.Paste" user)
		(15 "B.Paste" user)
		(5 "F.SilkS" user "F.Silkscreen")
		(7 "B.SilkS" user "B.Silkscreen")
		(1 "F.Mask" user)
		(3 "B.Mask" user)
		(17 "Dwgs.User" user "User.Drawings")
		(19 "Cmts.User" user "User.Comments")
		(21 "Eco1.User" user "User.Eco1")
		(23 "Eco2.User" user "User.Eco2")
		(25 "Edge.Cuts" user)
		(27 "Margin" user)
		(31 "F.CrtYd" user "F.Courtyard")
		(29 "B.CrtYd" user "B.Courtyard")
		(35 "F.Fab" user)
		(33 "B.Fab" user)
	)
	(footprint "antmicro-footprints:R_0402_1005Metric"
		(layer "B.Cu")
		(at 84.937962 165.0965)
		(descr "Resistor SMD 0402")
		(tags "resistor SMD 0402")
		(property "Reference" "R209"
			(at -3.62 0.53 0)
			(layer "B.SilkS")
			(effects
				(font
					(size 0.7 0.7)
					(thickness 0.15)
				)
				(justify right bottom mirror)
			)
		)
		(property "Value" "R_0R_0402"
			(at -1.011843 -1.772047 0)
			(layer "B.Fab")
			(effects
				(font
					(size 0.7 0.7)
					(thickness 0.15)
				)
				(justify right bottom mirror)
			)
		)
		(property "Datasheet" "https://industrial.panasonic.com/cdbs/www-data/pdf/RDA0000/AOA0000C301.pdf"
			(at 0 0 0)
			(layer "B.Fab")
			(hide yes)
			(effects
				(font
					(size 1.27 1.27)
					(thickness 0.15)
				)
			)
		)
		(property "Manufacturer" "Panasonic"
			(at 0 0 0)
			(unlocked yes)
			(layer "B.Fab")
			(hide yes)
			(effects
				(font
					(size 1 1)
					(thickness 0.15)
				)
				(justify mirror)
			)
		)
		(property "MPN" "ERJ2GE0R00X"
			(at 0 0 0)
			(unlocked yes)
			(layer "B.Fab")
			(hide yes)
			(effects
				(font
					(size 1 1)
					(thickness 0.15)
				)
				(justify mirror)
			)
		)
		(property "Val" "0R"
			(at 0 0 0)
			(unlocked yes)
			(layer "B.Fab")
			(hide yes)
			(effects
				(font
					(size 1 1)
					(thickness 0.15)
				)
				(justify mirror)
			)
		)
		(property "License" "Apache-2.0"
			(at 0 0 0)
			(unlocked yes)
			(layer "B.Fab")
			(hide yes)
			(effects
				(font
					(size 1 1)
					(thickness 0.15)
				)
				(justify mirror)
			)
		)
		(property "Author" "Antmicro"
			(at 0 0 0)
			(unlocked yes)
			(layer "B.Fab")
			(hide yes)
			(effects
				(font
					(size 1 1)
					(thickness 0.15)
				)
				(justify mirror)
			)
		)
		(property "Tolerance" "~"
			(at 0 0 0)
			(unlocked yes)
			(layer "B.Fab")
			(hide yes)
			(effects
				(font
					(size 1 1)
					(thickness 0.15)
				)
				(justify mirror)
			)
		)
		(property "Current" "1A"
			(at 0 0 0)
			(unlocked yes)
			(layer "B.Fab")
			(hide yes)
			(effects
				(font
					(size 1 1)
					(thickness 0.15)
				)
				(justify mirror)
			)
		)
		(sheetname "/Compute module/")
		(sheetfile "compute-module.kicad_sch")
		(attr smd exclude_from_pos_files exclude_from_bom dnp)
		(fp_rect
			(start -0.925 0.47)
			(end 0.925 -0.47)
			(stroke
				(width 0.05)
				(type default)
			)
			(fill no)
			(layer "B.CrtYd")
		)
		(fp_rect
			(start -0.5 0.25)
			(end 0.5 -0.25)
			(stroke
				(width 0.15)
				(type solid)
			)
			(fill no)
			(layer "B.Fab")
		)
		(fp_text user "Author: Antmicro"
			(at -0.95 -4.169 180)
			(layer "B.Fab")
			(effects
				(font
					(size 0.7 0.7)
					(thickness 0.15)
				)
				(justify left bottom mirror)
			)
		)
		(fp_text user "${REFERENCE}"
			(at -0.95 -3.168 180)
			(layer "B.Fab")
			(effects
				(font
					(size 0.7 0.7)
					(thickness 0.15)
				)
				(justify left bottom mirror)
			)
		)
		(fp_text user "License: Apache-2.0"
			(at -0.95 -5.169 180)
			(layer "B.Fab")
			(effects
				(font
					(size 0.7 0.7)
					(thickness 0.15)
				)
				(justify left bottom mirror)
			)
		)
		(pad "1" smd roundrect
			(at -0.48 0)
			(size 0.59 0.64)
			(layers "B.Cu" "B.Mask" "B.Paste")
			(roundrect_rratio 0.25)
			(net 254 "/Compute module/CAM_GPIO")
			(pintype "passive")
		)
		(pad "2" smd roundrect
			(at 0.48 0)
			(size 0.59 0.64)
			(layers "B.Cu" "B.Mask" "B.Paste")
			(roundrect_rratio 0.25)
			(net 275 "/CSI/CamCtrl.VSYNC1")
			(pintype "passive")
		)
	)
	(footprint "antmicro-footprints:Vishay_PowerPAK_1212-8_Single"
		(layer "B.Cu")
		(at 56.917962 163.3165 -90)
		(descr "PowerPAK 1212-8 Single")
		(tags "Vishay PowerPAK 1212-8 Single")
		(property "Reference" "Q305"
			(at -2.05 2 0)
			(layer "B.SilkS")
			(effects
				(font
					(size 0.7 0.7)
					(thickness 0.15)
				)
				(justify right bottom mirror)
			)
		)
		(property "Value" "SQS401EN-T1_BE3"
			(at 0 -2.7 90)
			(layer "B.Fab")
			(effects
				(font
					(size 0.7 0.7)
					(thickness 0.15)
				)
				(justify left bottom mirror)
			)
		)
		(property "Datasheet" "https://www.vishay.com/docs/65529/sqs401en.pdf"
			(at 0 0 270)
			(layer "B.Fab")
			(hide yes)
			(effects
				(font
					(size 1.27 1.27)
					(thickness 0.15)
				)
			)
		)
		(property "MPN" "SQS401EN-T1_BE3"
			(at 0 0 270)
			(unlocked yes)
			(layer "B.Fab")
			(hide yes)
			(effects
				(font
					(size 1 1)
					(thickness 0.15)
				)
				(justify mirror)
			)
		)
		(property "Manufacturer" "Vishay"
			(at 0 0 270)
			(unlocked yes)
			(layer "B.Fab")
			(hide yes)
			(effects
				(font
					(size 1 1)
					(thickness 0.15)
				)
				(justify mirror)
			)
		)
		(property "Author" "Antmicro"
			(at 0 0 270)
			(unlocked yes)
			(layer "B.Fab")
			(hide yes)
			(effects
				(font
					(size 1 1)
					(thickness 0.15)
				)
				(justify mirror)
			)
		)
		(property "License" "Apache-2.0"
			(at 0 0 270)
			(unlocked yes)
			(layer "B.Fab")
			(hide yes)
			(effects
				(font
					(size 1 1)
					(thickness 0.15)
				)
				(justify mirror)
			)
		)
		(sheetname "/Supply/")
		(sheetfile "supply.kicad_sch")
		(attr smd)
		(fp_line
			(start -1.651 1.651)
			(end 1.648 1.651)
			(stroke
				(width 0.15)
				(type solid)
			)
			(layer "B.SilkS")
		)
		(fp_line
			(start -1.651 1.651)
			(end -1.651 1.317)
			(stroke
				(width 0.15)
				(type solid)
			)
			(layer "B.SilkS")
		)
		(fp_line
			(start 1.648 1.651)
			(end 1.648 1.317)
			(stroke
				(width 0.15)
				(type solid)
			)
			(layer "B.SilkS")
		)
		(fp_line
			(start -1.635 -1.3)
			(end -1.635 -1.634)
			(stroke
				(width 0.15)
				(type solid)
			)
			(layer "B.SilkS")
		)
		(fp_line
			(start 1.634 -1.3)
			(end 1.634 -1.634)
			(stroke
				(width 0.15)
				(type solid)
			)
			(layer "B.SilkS")
		)
		(fp_line
			(start -1.635 -1.634)
			(end 1.634 -1.634)
			(stroke
				(width 0.15)
				(type solid)
			)
			(layer "B.SilkS")
		)
		(fp_circle
			(center -1.9 1.4)
			(end -1.85 1.4)
			(stroke
				(width 0.15)
				(type solid)
			)
			(fill yes)
			(layer "B.SilkS")
		)
		(fp_rect
			(start -2 1.8)
			(end 2 -1.798)
			(stroke
				(width 0.05)
				(type solid)
			)
			(fill no)
			(layer "B.CrtYd")
		)
		(fp_line
			(start -1.6425 1.4175)
			(end -1.4175 1.6425)
			(stroke
				(width 0.15)
				(type solid)
			)
			(layer "B.Fab")
		)
		(fp_rect
			(start -1.651 1.651)
			(end 1.648 -1.648)
			(stroke
				(width 0.15)
				(type solid)
			)
			(fill no)
			(layer "B.Fab")
		)
		(fp_text user "Author: Antmicro"
			(at -8 -5.9 90)
			(layer "B.Fab")
			(effects
				(font
					(size 0.7 0.7)
					(thickness 0.15)
				)
				(justify left bottom mirror)
			)
		)
		(fp_text user "License: Apache-2.0"
			(at -8 -7.1 90)
			(layer "B.Fab")
			(effects
				(font
					(size 0.7 0.7)
					(thickness 0.15)
				)
				(justify left bottom mirror)
			)
		)
		(fp_text user "${REFERENCE}"
			(at -8 -4.7 90)
			(layer "B.Fab")
			(effects
				(font
					(size 0.7 0.7)
					(thickness 0.15)
				)
				(justify left bottom mirror)
			)
		)
		(pad "1" smd rect
			(at -1.436 0.99 270)
			(size 0.99 0.405)
			(layers "B.Cu" "B.Mask" "B.Paste")
			(net 21 "/Supply/VCC_IN")
			(pinfunction "S")
			(pintype "passive")
		)
		(pad "2" smd rect
			(at -1.436 0.332 270)
			(size 0.99 0.405)
			(layers "B.Cu" "B.Mask" "B.Paste")
			(net 21 "/Supply/VCC_IN")
			(pinfunction "S")
			(pintype "passive")
		)
		(pad "3" smd rect
			(at -1.436 -0.33 270)
			(size 0.99 0.405)
			(layers "B.Cu" "B.Mask" "B.Paste")
			(net 21 "/Supply/VCC_IN")
			(pinfunction "S")
			(pintype "passive")
		)
		(pad "4" smd rect
			(at -1.436 -0.988 270)
			(size 0.99 0.405)
			(layers "B.Cu" "B.Mask" "B.Paste")
			(net 335 "Net-(Q302-BIAS)")
			(pinfunction "G")
			(pintype "input")
		)
		(pad "5" smd custom
			(at 0.557 0 270)
			(size 1.725 2.235)
			(layers "B.Cu" "B.Mask" "B.Paste")
			(net 47 "/Ethernet/POE_12V")
			(pinfunction "D")
			(pintype "passive")
			(zone_connect 2)
			(options
				(clearance outline)
				(anchor rect)
			)
			(primitives
				(gr_poly
					(pts
						(xy 0.8625 -0.1275) (xy 0.8625 0.1275) (xy 1.3725 0.1275) (xy 1.3725 0.5325) (xy 0.8625 0.5325)
						(xy 0.8625 0.7875) (xy 1.3725 0.7875) (xy 1.3725 1.195) (xy 0.6125 1.195) (xy 0.6125 -1.195) (xy 1.3725 -1.195)
						(xy 1.3725 -0.7875) (xy 0.8625 -0.7875) (xy 0.8625 -0.5325) (xy 1.3725 -0.5325) (xy 1.3725 -0.1275)
					)
					(width 0)
					(fill yes)
				)
			)
		)
	)
	(footprint "antmicro-footprints:C_0805_2012Metric"
		(layer "B.Cu")
		(at 116.217962 134.7165 90)
		(descr "Capacitor SMD 0805")
		(tags "capacitor SMD 0805")
		(property "Reference" "C313"
			(at -4.58 0.69 90)
			(layer "B.SilkS")
			(effects
				(font
					(size 0.7 0.7)
					(thickness 0.15)
				)
				(justify right bottom mirror)
			)
		)
		(property "Value" "C_22u_25V_0805"
			(at -2.055717 -1.963152 90)
			(layer "B.Fab")
			(effects
				(font
					(size 0.7 0.7)
					(thickness 0.15)
				)
				(justify right bottom mirror)
			)
		)
		(property "Datasheet" "https://product.samsungsem.com/mlcc/CL21A226MAYNNN.do"
			(at 0 0 90)
			(layer "B.Fab")
			(hide yes)
			(effects
				(font
					(size 1.27 1.27)
					(thickness 0.15)
				)
			)
		)
		(property "Manufacturer" "Samsung Electro-Mechanics"
			(at 0 0 90)
			(unlocked yes)
			(layer "B.Fab")
			(hide yes)
			(effects
				(font
					(size 1 1)
					(thickness 0.15)
				)
				(justify mirror)
			)
		)
		(property "MPN" "CL21A226MAYNNNE"
			(at 0 0 90)
			(unlocked yes)
			(layer "B.Fab")
			(hide yes)
			(effects
				(font
					(size 1 1)
					(thickness 0.15)
				)
				(justify mirror)
			)
		)
		(property "Val" "22u"
			(at 0 0 90)
			(unlocked yes)
			(layer "B.Fab")
			(hide yes)
			(effects
				(font
					(size 1 1)
					(thickness 0.15)
				)
				(justify mirror)
			)
		)
		(property "License" "Apache-2.0"
			(at 0 0 90)
			(unlocked yes)
			(layer "B.Fab")
			(hide yes)
			(effects
				(font
					(size 1 1)
					(thickness 0.15)
				)
				(justify mirror)
			)
		)
		(property "Author" "Antmicro"
			(at 0 0 90)
			(unlocked yes)
			(layer "B.Fab")
			(hide yes)
			(effects
				(font
					(size 1 1)
					(thickness 0.15)
				)
				(justify mirror)
			)
		)
		(property "Voltage" "25V"
			(at 0 0 90)
			(unlocked yes)
			(layer "B.Fab")
			(hide yes)
			(effects
				(font
					(size 1 1)
					(thickness 0.15)
				)
				(justify mirror)
			)
		)
		(property "Dielectric" "X5R"
			(at 0 0 90)
			(unlocked yes)
			(layer "B.Fab")
			(hide yes)
			(effects
				(font
					(size 1 1)
					(thickness 0.15)
				)
				(justify mirror)
			)
		)
		(property "Public" "False"
			(at 0 0 90)
			(unlocked yes)
			(layer "B.Fab")
			(hide yes)
			(effects
				(font
					(size 1 1)
					(thickness 0.15)
				)
				(justify mirror)
			)
		)
		(sheetname "/Supply/")
		(sheetfile "supply.kicad_sch")
		(attr smd)
		(fp_line
			(start -0.3 -0.7)
			(end 0.3 -0.7)
			(stroke
				(width 0.15)
				(type solid)
			)
			(layer "B.SilkS")
		)
		(fp_line
			(start -0.3 0.7)
			(end 0.3 0.7)
			(stroke
				(width 0.15)
				(type solid)
			)
			(layer "B.SilkS")
		)
		(fp_rect
			(start 1.95 0.9)
			(end -1.95 -0.9)
			(stroke
				(width 0.05)
				(type default)
			)
			(fill no)
			(layer "B.CrtYd")
		)
		(fp_rect
			(start -0.95 0.675)
			(end 0.95 -0.675)
			(stroke
				(width 0.15)
				(type solid)
			)
			(fill no)
			(layer "B.Fab")
		)
		(fp_text user "License: Apache-2.0"
			(at -1.9 -4.947 270)
			(layer "B.Fab")
			(effects
				(font
					(size 0.7 0.7)
					(thickness 0.15)
				)
				(justify left bottom mirror)
			)
		)
		(fp_text user "Author: Antmicro"
			(at -1.9 -5.947 270)
			(layer "B.Fab")
			(effects
				(font
					(size 0.7 0.7)
					(thickness 0.15)
				)
				(justify left bottom mirror)
			)
		)
		(fp_text user "${REFERENCE}"
			(at -1.9 -3.947 270)
			(layer "B.Fab")
			(effects
				(font
					(size 0.7 0.7)
					(thickness 0.15)
				)
				(justify left bottom mirror)
			)
		)
		(pad "1" smd roundrect
			(at -1.1 0 90)
			(size 1.2 1.3)
			(layers "B.Cu" "B.Mask" "B.Paste")
			(roundrect_rratio 0.25)
			(net 78 "/Supply/OUT_M2")
			(pintype "passive")
		)
		(pad "2" smd roundrect
			(at 1.1 0 90)
			(size 1.2 1.3)
			(layers "B.Cu" "B.Mask" "B.Paste")
			(roundrect_rratio 0.25)
			(net 3 "GND")
			(pintype "passive")
		)
	)
	(footprint "antmicro-footprints:Vishay_PowerPAK_1212-8_Single"
		(layer "B.Cu")
		(at 42.602962 163.2805 -90)
		(descr "PowerPAK 1212-8 Single")
		(tags "Vishay PowerPAK 1212-8 Single")
		(property "Reference" "Q304"
			(at -1.964 1.485 0)
			(layer "B.SilkS")
			(effects
				(font
					(size 0.7 0.7)
					(thickness 0.15)
				)
				(justify right bottom mirror)
			)
		)
		(property "Value" "SQS401EN-T1_BE3"
			(at 0 -2.7 90)
			(layer "B.Fab")
			(effects
				(font
					(size 0.7 0.7)
					(thickness 0.15)
				)
				(justify left bottom mirror)
			)
		)
		(property "Datasheet" "https://www.vishay.com/docs/65529/sqs401en.pdf"
			(at 0 0 270)
			(layer "B.Fab")
			(hide yes)
			(effects
				(font
					(size 1.27 1.27)
					(thickness 0.15)
				)
			)
		)
		(property "MPN" "SQS401EN-T1_BE3"
			(at 0 0 270)
			(unlocked yes)
			(layer "B.Fab")
			(hide yes)
			(effects
				(font
					(size 1 1)
					(thickness 0.15)
				)
				(justify mirror)
			)
		)
		(property "Manufacturer" "Vishay"
			(at 0 0 270)
			(unlocked yes)
			(layer "B.Fab")
			(hide yes)
			(effects
				(font
					(size 1 1)
					(thickness 0.15)
				)
				(justify mirror)
			)
		)
		(property "Author" "Antmicro"
			(at 0 0 270)
			(unlocked yes)
			(layer "B.Fab")
			(hide yes)
			(effects
				(font
					(size 1 1)
					(thickness 0.15)
				)
				(justify mirror)
			)
		)
		(property "License" "Apache-2.0"
			(at 0 0 270)
			(unlocked yes)
			(layer "B.Fab")
			(hide yes)
			(effects
				(font
					(size 1 1)
					(thickness 0.15)
				)
				(justify mirror)
			)
		)
		(sheetname "/Supply/")
		(sheetfile "supply.kicad_sch")
		(attr smd)
		(fp_line
			(start -1.651 1.651)
			(end 1.648 1.651)
			(stroke
				(width 0.15)
				(type solid)
			)
			(layer "B.SilkS")
		)
		(fp_line
			(start -1.651 1.651)
			(end -1.651 1.317)
			(stroke
				(width 0.15)
				(type solid)
			)
			(layer "B.SilkS")
		)
		(fp_line
			(start 1.648 1.651)
			(end 1.648 1.317)
			(stroke
				(width 0.15)
				(type solid)
			)
			(layer "B.SilkS")
		)
		(fp_line
			(start -1.635 -1.3)
			(end -1.635 -1.634)
			(stroke
				(width 0.15)
				(type solid)
			)
			(layer "B.SilkS")
		)
		(fp_line
			(start 1.634 -1.3)
			(end 1.634 -1.634)
			(stroke
				(width 0.15)
				(type solid)
			)
			(layer "B.SilkS")
		)
		(fp_line
			(start -1.635 -1.634)
			(end 1.634 -1.634)
			(stroke
				(width 0.15)
				(type solid)
			)
			(layer "B.SilkS")
		)
		(fp_circle
			(center -1.9 1.4)
			(end -1.85 1.4)
			(stroke
				(width 0.15)
				(type solid)
			)
			(fill yes)
			(layer "B.SilkS")
		)
		(fp_rect
			(start -2 1.8)
			(end 2 -1.798)
			(stroke
				(width 0.05)
				(type solid)
			)
			(fill no)
			(layer "B.CrtYd")
		)
		(fp_line
			(start -1.6425 1.4175)
			(end -1.4175 1.6425)
			(stroke
				(width 0.15)
				(type solid)
			)
			(layer "B.Fab")
		)
		(fp_rect
			(start -1.651 1.651)
			(end 1.648 -1.648)
			(stroke
				(width 0.15)
				(type solid)
			)
			(fill no)
			(layer "B.Fab")
		)
		(fp_text user "Author: Antmicro"
			(at -8 -5.9 90)
			(layer "B.Fab")
			(effects
				(font
					(size 0.7 0.7)
					(thickness 0.15)
				)
				(justify left bottom mirror)
			)
		)
		(fp_text user "License: Apache-2.0"
			(at -8 -7.1 90)
			(layer "B.Fab")
			(effects
				(font
					(size 0.7 0.7)
					(thickness 0.15)
				)
				(justify left bottom mirror)
			)
		)
		(fp_text user "${REFERENCE}"
			(at -8 -4.7 90)
			(layer "B.Fab")
			(effects
				(font
					(size 0.7 0.7)
					(thickness 0.15)
				)
				(justify left bottom mirror)
			)
		)
		(pad "1" smd rect
			(at -1.436 0.99 270)
			(size 0.99 0.405)
			(layers "B.Cu" "B.Mask" "B.Paste")
			(net 21 "/Supply/VCC_IN")
			(pinfunction "S")
			(pintype "passive")
		)
		(pad "2" smd rect
			(at -1.436 0.332 270)
			(size 0.99 0.405)
			(layers "B.Cu" "B.Mask" "B.Paste")
			(net 21 "/Supply/VCC_IN")
			(pinfunction "S")
			(pintype "passive")
		)
		(pad "3" smd rect
			(at -1.436 -0.33 270)
			(size 0.99 0.405)
			(layers "B.Cu" "B.Mask" "B.Paste")
			(net 21 "/Supply/VCC_IN")
			(pinfunction "S")
			(pintype "passive")
		)
		(pad "4" smd rect
			(at -1.436 -0.988 270)
			(size 0.99 0.405)
			(layers "B.Cu" "B.Mask" "B.Paste")
			(net 333 "Net-(Q301-BIAS)")
			(pinfunction "G")
			(pintype "input")
		)
		(pad "5" smd custom
			(at 0.557 0 270)
			(size 1.725 2.235)
			(layers "B.Cu" "B.Mask" "B.Paste")
			(net 472 "Net-(D301-C)")
			(pinfunction "D")
			(pintype "passive")
			(zone_connect 2)
			(options
				(clearance outline)
				(anchor rect)
			)
			(primitives
				(gr_poly
					(pts
						(xy 0.8625 -0.1275) (xy 0.8625 0.1275) (xy 1.3725 0.1275) (xy 1.3725 0.5325) (xy 0.8625 0.5325)
						(xy 0.8625 0.7875) (xy 1.3725 0.7875) (xy 1.3725 1.195) (xy 0.6125 1.195) (xy 0.6125 -1.195) (xy 1.3725 -1.195)
						(xy 1.3725 -0.7875) (xy 0.8625 -0.7875) (xy 0.8625 -0.5325) (xy 1.3725 -0.5325) (xy 1.3725 -0.1275)
					)
					(width 0)
					(fill yes)
				)
			)
		)
	)
)
